FILE_TYPE = MACRO_DRAWING;
SET COLOR_WIRE YELLOW;
SET COLOR_PROP ORANGE;
SET COLOR_DOT WHITE;
SET COLOR_ARC YELLOW;
SET COLOR_BODY GREEN;
SET COLOR_NOTE PURPLE;
SET PROP_DISPLAY VALUE;
SET PAGE_NUMBER P1;
FORCEADD SYNONYM..1
(2100 2100);
FORCEPROP 2 LASTPIN (2050 2100) SIG_NAME GND\G
J 2
(2000 2110);
DISPLAY 0.872340 (2000 2110);
FORCEPROP 2 LAST PATH 1P
J 0
(2100 2200);
DISPLAY 0.872340 (2100 2200);
FORCEPROP 2 LASTPIN (2150 2100) SIG_NAME A\I
J 0
(2200 2110);
DISPLAY 0.872340 (2200 2110);
FORCEPROP 2 LAST CDS_LIB mstr_standard
J 0
(2100 2100);
DISPLAY INVISIBLE (2100 2100);
FORCEPROP 1 LAST NEEDS_NO_SIZE TRUE
J 0
(2125 2175);
DISPLAY 0.872340 (2125 2175);
PAINT GREEN (2125 2175);
DISPLAY INVISIBLE (2125 2175);
FORCEPROP 1 LAST BODY_TYPE PLUMBING
J 0
(2100 2150);
DISPLAY 0.872340 (2100 2150);
PAINT SKYBLUE (2100 2150);
DISPLAY INVISIBLE (2100 2150);
FORCEADD DRAWING..1
(2350 1750);
FORCEPROP 0 LAST TITLE GND
J 0
(2200 1700);
DISPLAY 0.872340 (2200 1700);
DISPLAY BOTH (2200 1700);
FORCEPROP 1 LAST LAST_MODIFIED Mon Aug 22 14:31:23 2011
J 0
(2150 1500);
DISPLAY 0.872340 (2150 1500);
PAINT GREEN (2150 1500);
DISPLAY BOTH (2150 1500);
FORCEPROP 0 LAST ABBREV GND
J 0
(2200 1600);
DISPLAY 0.872340 (2200 1600);
DISPLAY BOTH (2200 1600);
QUIT
